(kicad_pcb
	(version 20260206)
	(generator "pcbnew")
	(generator_version "10.0")
	(general
		(thickness 1.6)
		(legacy_teardrops no)
	)
	(paper "A4")
	(title_block
		(title "Bryce Canyon_SCC_16316-1_OCP.brd")
		(comment 1 "Bryce Canyon / footprints 888-894 of 1561")
	)
	(layers
		(0 "F.Cu" signal "TOP")
		(4 "In1.Cu" signal "L2GND")
		(6 "In2.Cu" signal "L3")
		(8 "In3.Cu" signal "L4VCC")
		(10 "In4.Cu" signal "L5VCC")
		(12 "In5.Cu" signal "L6")
		(14 "In6.Cu" signal "L7GND")
		(2 "B.Cu" signal "BOTTOM")
		(9 "F.Adhes" user "F.Adhesive")
		(11 "B.Adhes" user "B.Adhesive")
		(13 "F.Paste" user "Package Geometry/Pastemask Top")
		(15 "B.Paste" user "Package Geometry/Pastemask Bottom")
		(5 "F.SilkS" user "Ref Des/Silkscreen Top")
		(7 "B.SilkS" user "Ref Des/Silkscreen Bottom")
		(1 "F.Mask" user "Board Geometry/Soldermask Top")
		(3 "B.Mask" user "Board Geometry/Soldermask Bottom")
		(17 "Dwgs.User" user "User.Drawings")
		(19 "Cmts.User" user "User.Comments")
		(21 "Eco1.User" user "User.Eco1")
		(23 "Eco2.User" user "User.Eco2")
		(25 "Edge.Cuts" user "Board Geometry/Outline")
		(27 "Margin" user)
		(31 "F.CrtYd" user "Package Geometry/Place Bound Top")
		(29 "B.CrtYd" user "Package Geometry/Place Bound Bottom")
		(35 "F.Fab" user "Ref Des/Assembly Top")
		(33 "B.Fab" user "Ref Des/Assembly Bottom")
	)
	(footprint ""
		(layer "B.Cu")
		(at 73.66 -36.068)
		(property "Reference" "C227"
			(at 0 0 0)
			(layer "B.SilkS")
			(hide yes)
			(effects
				(font
					(size 1.27 1.27)
				)
				(justify mirror)
			)
		)
		(property "Value" "SC100U6D3V6MX-GP"
			(at 0.0762 -5.1308 0)
			(unlocked yes)
			(layer "B.Fab")
			(hide yes)
			(effects
				(font
					(size 1.016 1.016)
					(thickness 0.1524)
				)
				(justify mirror)
			)
		)
		(property "Device Type" "C1206H71"
			(at 0.127 -6.6548 0)
			(unlocked yes)
			(layer "B.Fab")
			(hide yes)
			(effects
				(font
					(size 1.016 1.016)
					(thickness 0.1524)
				)
				(justify mirror)
			)
		)
		(duplicate_pad_numbers_are_jumpers no)
		(fp_line
			(start -1.016 -2.2352)
			(end -1.016 -0.8382)
			(stroke
				(width 0.1524)
				(type default)
			)
			(layer "B.SilkS")
		)
		(fp_line
			(start -1.016 0.8382)
			(end -1.016 2.2352)
			(stroke
				(width 0.1524)
				(type default)
			)
			(layer "B.SilkS")
		)
		(fp_line
			(start -1.016 2.2352)
			(end 1.016 2.2352)
			(stroke
				(width 0.1524)
				(type default)
			)
			(layer "B.SilkS")
		)
		(fp_line
			(start 1.016 -2.2352)
			(end -1.016 -2.2352)
			(stroke
				(width 0.1524)
				(type default)
			)
			(layer "B.SilkS")
		)
		(fp_line
			(start 1.016 -0.8382)
			(end 1.016 -2.2352)
			(stroke
				(width 0.1524)
				(type default)
			)
			(layer "B.SilkS")
		)
		(fp_line
			(start 1.016 2.2352)
			(end 1.016 0.8382)
			(stroke
				(width 0.1524)
				(type default)
			)
			(layer "B.SilkS")
		)
		(fp_rect
			(start 1.0922 2.3114)
			(end -1.0922 -2.3114)
			(stroke
				(width 0)
				(type default)
			)
			(fill no)
			(layer "B.CrtYd")
		)
		(fp_poly
			(pts
				(xy -1.0922 -2.3114) (xy -1.0922 2.3114) (xy 1.0922 2.3114) (xy 1.0922 -2.3114)
			)
			(stroke
				(width 0)
				(type default)
			)
			(fill no)
			(layer "B.Fab")
		)
		(pad "1" smd rect
			(at 0 -1.397 180)
			(size 1.651 1.27)
			(layers "B.Cu" "B.Mask" "B.Paste")
			(net "GB_VDDA")
		)
		(pad "2" smd rect
			(at 0 1.397 180)
			(size 1.651 1.27)
			(layers "B.Cu" "B.Mask" "B.Paste")
			(net "GND")
		)
	)
	(footprint ""
		(layer "B.Cu")
		(at 137.414 -74.5998 -90)
		(property "Reference" "C9"
			(at 0 0 90)
			(layer "B.SilkS")
			(hide yes)
			(effects
				(font
					(size 1.27 1.27)
				)
				(justify mirror)
			)
		)
		(property "Value" "SCD01U16V1KX-GP"
			(at 2.8321 -1.7399 270)
			(unlocked yes)
			(layer "B.Fab")
			(hide yes)
			(effects
				(font
					(size 1.016 1.016)
					(thickness 0.1524)
				)
				(justify mirror)
			)
		)
		(property "Device Type" "C0201H13"
			(at 2.8321 -3.2639 270)
			(unlocked yes)
			(layer "B.Fab")
			(hide yes)
			(effects
				(font
					(size 1.016 1.016)
					(thickness 0.1524)
				)
				(justify mirror)
			)
		)
		(duplicate_pad_numbers_are_jumpers no)
		(fp_rect
			(start 0.2794 0.6477)
			(end -0.2794 -0.6477)
			(stroke
				(width 0)
				(type default)
			)
			(fill no)
			(layer "B.CrtYd")
		)
		(fp_rect
			(start 0.2794 0.6477)
			(end -0.2794 -0.6477)
			(stroke
				(width 0)
				(type default)
			)
			(fill no)
			(layer "B.Fab")
		)
		(pad "1" smd custom
			(at 0 -0.2794 90)
			(size 0.0762 0.0762)
			(layers "B.Cu" "B.Mask" "B.Paste")
			(net "PHY_DPB_TO_SCC_7_DP")
			(options
				(clearance outline)
				(anchor circle)
			)
			(primitives
				(gr_poly
					(pts
						(arc
							(start 0.1524 0.127)
							(mid 0.137521 0.162921)
							(end 0.1016 0.1778)
						)
						(arc
							(start -0.1016 0.1778)
							(mid -0.137521 0.162921)
							(end -0.1524 0.127)
						)
						(arc
							(start -0.1524 -0.127)
							(mid -0.137521 -0.162921)
							(end -0.1016 -0.1778)
						)
						(arc
							(start 0.1016 -0.1778)
							(mid 0.137521 -0.162921)
							(end 0.1524 -0.127)
						)
					)
					(width 0)
					(fill yes)
				)
			)
		)
		(pad "2" smd custom
			(at 0 0.2794 90)
			(size 0.0762 0.0762)
			(layers "B.Cu" "B.Mask" "B.Paste")
			(net "PHY_DPB_TO_SCC_C_7_DP")
			(options
				(clearance outline)
				(anchor circle)
			)
			(primitives
				(gr_poly
					(pts
						(arc
							(start 0.1524 0.127)
							(mid 0.137521 0.162921)
							(end 0.1016 0.1778)
						)
						(arc
							(start -0.1016 0.1778)
							(mid -0.137521 0.162921)
							(end -0.1524 0.127)
						)
						(arc
							(start -0.1524 -0.127)
							(mid -0.137521 -0.162921)
							(end -0.1016 -0.1778)
						)
						(arc
							(start 0.1016 -0.1778)
							(mid 0.137521 -0.162921)
							(end 0.1524 -0.127)
						)
					)
					(width 0)
					(fill yes)
				)
			)
		)
	)
	(footprint ""
		(layer "B.Cu")
		(at 167.7162 -38.5572 180)
		(property "Reference" "C400"
			(at 0 0 0)
			(layer "B.SilkS")
			(hide yes)
			(effects
				(font
					(size 1.27 1.27)
				)
				(justify mirror)
			)
		)
		(property "Value" "SCD1U16V2KX-3GP"
			(at -1.1811 -2.7051 180)
			(unlocked yes)
			(layer "B.Fab")
			(hide yes)
			(effects
				(font
					(size 1.016 1.016)
					(thickness 0.1524)
				)
				(justify mirror)
			)
		)
		(property "Device Type" "C402H22"
			(at -1.1811 -4.2291 180)
			(unlocked yes)
			(layer "B.Fab")
			(hide yes)
			(effects
				(font
					(size 1.016 1.016)
					(thickness 0.1524)
				)
				(justify mirror)
			)
		)
		(duplicate_pad_numbers_are_jumpers no)
		(fp_rect
			(start 0.4318 0.9525)
			(end -0.4318 -0.9525)
			(stroke
				(width 0)
				(type default)
			)
			(fill no)
			(layer "B.CrtYd")
		)
		(fp_rect
			(start 0.4318 0.9525)
			(end -0.4318 -0.9525)
			(stroke
				(width 0)
				(type default)
			)
			(fill no)
			(layer "B.Fab")
		)
		(pad "1" smd custom
			(at 0 -0.4445)
			(size 0.1524 0.1524)
			(layers "B.Cu" "B.Mask" "B.Paste")
			(net "SAS0_AVDD")
			(options
				(clearance outline)
				(anchor circle)
			)
			(primitives
				(gr_poly
					(pts
						(arc
							(start 0.3048 0.2032)
							(mid 0.275042 0.275042)
							(end 0.2032 0.3048)
						)
						(arc
							(start -0.2032 0.3048)
							(mid -0.275042 0.275042)
							(end -0.3048 0.2032)
						)
						(arc
							(start -0.3048 -0.2032)
							(mid -0.275042 -0.275042)
							(end -0.2032 -0.3048)
						)
						(arc
							(start 0.2032 -0.3048)
							(mid 0.275042 -0.275042)
							(end 0.3048 -0.2032)
						)
					)
					(width 0)
					(fill yes)
				)
			)
		)
		(pad "2" smd custom
			(at 0 0.4445)
			(size 0.1524 0.1524)
			(layers "B.Cu" "B.Mask" "B.Paste")
			(net "GND")
			(options
				(clearance outline)
				(anchor circle)
			)
			(primitives
				(gr_poly
					(pts
						(arc
							(start 0.3048 0.2032)
							(mid 0.275042 0.275042)
							(end 0.2032 0.3048)
						)
						(arc
							(start -0.2032 0.3048)
							(mid -0.275042 0.275042)
							(end -0.3048 0.2032)
						)
						(arc
							(start -0.3048 -0.2032)
							(mid -0.275042 -0.275042)
							(end -0.2032 -0.3048)
						)
						(arc
							(start 0.2032 -0.3048)
							(mid 0.275042 -0.275042)
							(end 0.3048 -0.2032)
						)
					)
					(width 0)
					(fill yes)
				)
			)
		)
	)
	(footprint ""
		(layer "B.Cu")
		(at 123.5075 -72.7329 180)
		(property "Reference" "C243"
			(at 0 0 0)
			(layer "B.SilkS")
			(hide yes)
			(effects
				(font
					(size 1.27 1.27)
				)
				(justify mirror)
			)
		)
		(property "Value" "SC1U6D3V1MX-GP"
			(at -1.9177 2.0193 180)
			(unlocked yes)
			(layer "B.Fab")
			(hide yes)
			(effects
				(font
					(size 1.016 1.016)
					(thickness 0.1524)
				)
				(justify mirror)
			)
		)
		(property "Device Type" "C0201H14"
			(at -1.9177 0.4953 180)
			(unlocked yes)
			(layer "B.Fab")
			(hide yes)
			(effects
				(font
					(size 1.016 1.016)
					(thickness 0.1524)
				)
				(justify mirror)
			)
		)
		(duplicate_pad_numbers_are_jumpers no)
		(fp_rect
			(start 0.1524 0.3048)
			(end -0.1524 -0.3048)
			(stroke
				(width 0)
				(type default)
			)
			(fill no)
			(layer "B.CrtYd")
		)
		(fp_poly
			(pts
				(xy 0.2794 0.6477) (xy 0.2794 -0.6477) (xy -0.2794 -0.6477) (xy -0.2794 -0.1905) (xy -0.1524 -0.1905)
				(xy -0.1524 -0.3048) (xy 0.1524 -0.3048) (xy 0.1524 0.3048) (xy -0.1524 0.3048) (xy -0.1524 -0.1778)
				(xy -0.2794 -0.1778) (xy -0.2794 0.6477)
			)
			(stroke
				(width 0)
				(type default)
			)
			(fill no)
			(layer "B.CrtYd")
		)
		(fp_rect
			(start 0.2794 0.6477)
			(end -0.2794 -0.6477)
			(stroke
				(width 0)
				(type default)
			)
			(fill no)
			(layer "B.Fab")
		)
		(pad "1" smd custom
			(at 0 -0.2794)
			(size 0.0762 0.0762)
			(layers "B.Cu" "B.Mask" "B.Paste")
			(net "GB_VDDA")
			(options
				(clearance outline)
				(anchor circle)
			)
			(primitives
				(gr_poly
					(pts
						(arc
							(start 0.1524 0.127)
							(mid 0.137521 0.162921)
							(end 0.1016 0.1778)
						)
						(arc
							(start -0.1016 0.1778)
							(mid -0.137521 0.162921)
							(end -0.1524 0.127)
						)
						(arc
							(start -0.1524 -0.127)
							(mid -0.137521 -0.162921)
							(end -0.1016 -0.1778)
						)
						(arc
							(start 0.1016 -0.1778)
							(mid 0.137521 -0.162921)
							(end 0.1524 -0.127)
						)
					)
					(width 0)
					(fill yes)
				)
			)
		)
		(pad "2" smd custom
			(at 0 0.2794)
			(size 0.0762 0.0762)
			(layers "B.Cu" "B.Mask" "B.Paste")
			(net "GND")
			(options
				(clearance outline)
				(anchor circle)
			)
			(primitives
				(gr_poly
					(pts
						(arc
							(start 0.1524 0.127)
							(mid 0.137521 0.162921)
							(end 0.1016 0.1778)
						)
						(arc
							(start -0.1016 0.1778)
							(mid -0.137521 0.162921)
							(end -0.1524 0.127)
						)
						(arc
							(start -0.1524 -0.127)
							(mid -0.137521 -0.162921)
							(end -0.1016 -0.1778)
						)
						(arc
							(start 0.1016 -0.1778)
							(mid 0.137521 -0.162921)
							(end 0.1524 -0.127)
						)
					)
					(width 0)
					(fill yes)
				)
			)
		)
	)
	(footprint ""
		(layer "B.Cu")
		(at 120.0658 -44.2214 180)
		(property "Reference" "C57"
			(at 0 0 0)
			(layer "B.SilkS")
			(hide yes)
			(effects
				(font
					(size 1.27 1.27)
				)
				(justify mirror)
			)
		)
		(property "Value" "SCD01U16V1KX-GP"
			(at 2.8321 -1.7399 180)
			(unlocked yes)
			(layer "B.Fab")
			(hide yes)
			(effects
				(font
					(size 1.016 1.016)
					(thickness 0.1524)
				)
				(justify mirror)
			)
		)
		(property "Device Type" "C0201H13"
			(at 2.8321 -3.2639 180)
			(unlocked yes)
			(layer "B.Fab")
			(hide yes)
			(effects
				(font
					(size 1.016 1.016)
					(thickness 0.1524)
				)
				(justify mirror)
			)
		)
		(duplicate_pad_numbers_are_jumpers no)
		(fp_rect
			(start 0.2794 0.6477)
			(end -0.2794 -0.6477)
			(stroke
				(width 0)
				(type default)
			)
			(fill no)
			(layer "B.CrtYd")
		)
		(fp_rect
			(start 0.2794 0.6477)
			(end -0.2794 -0.6477)
			(stroke
				(width 0)
				(type default)
			)
			(fill no)
			(layer "B.Fab")
		)
		(pad "1" smd custom
			(at 0 -0.2794)
			(size 0.0762 0.0762)
			(layers "B.Cu" "B.Mask" "B.Paste")
			(net "PHY_DPB_TO_SCC_35_DP")
			(options
				(clearance outline)
				(anchor circle)
			)
			(primitives
				(gr_poly
					(pts
						(arc
							(start 0.1524 0.127)
							(mid 0.137521 0.162921)
							(end 0.1016 0.1778)
						)
						(arc
							(start -0.1016 0.1778)
							(mid -0.137521 0.162921)
							(end -0.1524 0.127)
						)
						(arc
							(start -0.1524 -0.127)
							(mid -0.137521 -0.162921)
							(end -0.1016 -0.1778)
						)
						(arc
							(start 0.1016 -0.1778)
							(mid 0.137521 -0.162921)
							(end 0.1524 -0.127)
						)
					)
					(width 0)
					(fill yes)
				)
			)
		)
		(pad "2" smd custom
			(at 0 0.2794)
			(size 0.0762 0.0762)
			(layers "B.Cu" "B.Mask" "B.Paste")
			(net "PHY_DPB_TO_SCC_C_35_DP")
			(options
				(clearance outline)
				(anchor circle)
			)
			(primitives
				(gr_poly
					(pts
						(arc
							(start 0.1524 0.127)
							(mid 0.137521 0.162921)
							(end 0.1016 0.1778)
						)
						(arc
							(start -0.1016 0.1778)
							(mid -0.137521 0.162921)
							(end -0.1524 0.127)
						)
						(arc
							(start -0.1524 -0.127)
							(mid -0.137521 -0.162921)
							(end -0.1016 -0.1778)
						)
						(arc
							(start 0.1016 -0.1778)
							(mid 0.137521 -0.162921)
							(end 0.1524 -0.127)
						)
					)
					(width 0)
					(fill yes)
				)
			)
		)
	)
	(footprint ""
		(layer "B.Cu")
		(at 108.585 -86.9442)
		(property "Reference" "R114"
			(at 0 0 0)
			(layer "B.SilkS")
			(hide yes)
			(effects
				(font
					(size 1.27 1.27)
				)
				(justify mirror)
			)
		)
		(property "Value" "4K75R2F-1-GP"
			(at -0.064008 -3.993896 0)
			(unlocked yes)
			(layer "B.Fab")
			(hide yes)
			(effects
				(font
					(size 1.016 1.016)
					(thickness 0.1524)
				)
				(justify mirror)
			)
		)
		(property "Device Type" "R402H16"
			(at -0.064008 -5.517896 0)
			(unlocked yes)
			(layer "B.Fab")
			(hide yes)
			(effects
				(font
					(size 1.016 1.016)
					(thickness 0.1524)
				)
				(justify mirror)
			)
		)
		(duplicate_pad_numbers_are_jumpers no)
		(fp_line
			(start -0.508 -0.9398)
			(end 0.508 -0.9398)
			(stroke
				(width 0.1524)
				(type default)
			)
			(layer "B.SilkS")
		)
		(fp_line
			(start 0.508 -0.9398)
			(end 0.508 0.9398)
			(stroke
				(width 0.1524)
				(type default)
			)
			(layer "B.SilkS")
		)
		(fp_rect
			(start 0.508 0.9398)
			(end -0.508 -0.9398)
			(stroke
				(width 0)
				(type default)
			)
			(fill no)
			(layer "B.CrtYd")
		)
		(fp_rect
			(start 0.508 0.9398)
			(end -0.508 -0.9398)
			(stroke
				(width 0)
				(type default)
			)
			(fill no)
			(layer "B.Fab")
		)
		(pad "1" smd custom
			(at 0 -0.4445 180)
			(size 0.1397 0.1397)
			(layers "B.Cu" "B.Mask" "B.Paste")
			(net "TMUX_EN")
			(options
				(clearance outline)
				(anchor circle)
			)
			(primitives
				(gr_poly
					(pts
						(arc
							(start -0.1778 0.2794)
							(mid -0.249642 0.249642)
							(end -0.2794 0.1778)
						)
						(arc
							(start -0.2794 -0.1778)
							(mid -0.249642 -0.249642)
							(end -0.1778 -0.2794)
						)
						(arc
							(start 0.1778 -0.2794)
							(mid 0.249642 -0.249642)
							(end 0.2794 -0.1778)
						)
						(arc
							(start 0.2794 0.1778)
							(mid 0.249642 0.249642)
							(end 0.1778 0.2794)
						)
					)
					(width 0)
					(fill yes)
				)
			)
		)
		(pad "2" smd custom
			(at 0 0.4445 180)
			(size 0.1397 0.1397)
			(layers "B.Cu" "B.Mask" "B.Paste")
			(net "GND")
			(options
				(clearance outline)
				(anchor circle)
			)
			(primitives
				(gr_poly
					(pts
						(arc
							(start -0.1778 0.2794)
							(mid -0.249642 0.249642)
							(end -0.2794 0.1778)
						)
						(arc
							(start -0.2794 -0.1778)
							(mid -0.249642 -0.249642)
							(end -0.1778 -0.2794)
						)
						(arc
							(start 0.1778 -0.2794)
							(mid 0.249642 -0.249642)
							(end 0.2794 -0.1778)
						)
						(arc
							(start 0.2794 0.1778)
							(mid 0.249642 0.249642)
							(end 0.1778 0.2794)
						)
					)
					(width 0)
					(fill yes)
				)
			)
		)
	)
	(footprint ""
		(layer "B.Cu")
		(at 107.106466 -67.01409 -90)
		(property "Reference" "R475"
			(at 0 0 90)
			(layer "B.SilkS")
			(hide yes)
			(effects
				(font
					(size 1.27 1.27)
				)
				(justify mirror)
			)
		)
		(property "Value" "0R2F-1-GP"
			(at -0.064008 -3.993896 270)
			(unlocked yes)
			(layer "B.Fab")
			(hide yes)
			(effects
				(font
					(size 1.016 1.016)
					(thickness 0.1524)
				)
				(justify mirror)
			)
		)
		(property "Device Type" "R402H16"
			(at -0.064008 -5.517896 270)
			(unlocked yes)
			(layer "B.Fab")
			(hide yes)
			(effects
				(font
					(size 1.016 1.016)
					(thickness 0.1524)
				)
				(justify mirror)
			)
		)
		(duplicate_pad_numbers_are_jumpers no)
		(fp_line
			(start -0.508 -0.9398)
			(end 0.508 -0.9398)
			(stroke
				(width 0.1524)
				(type default)
			)
			(layer "B.SilkS")
		)
		(fp_line
			(start 0.508 -0.9398)
			(end 0.508 0.9398)
			(stroke
				(width 0.1524)
				(type default)
			)
			(layer "B.SilkS")
		)
		(fp_rect
			(start 0.508 0.9398)
			(end -0.508 -0.9398)
			(stroke
				(width 0)
				(type default)
			)
			(fill no)
			(layer "B.CrtYd")
		)
		(fp_rect
			(start 0.508 0.9398)
			(end -0.508 -0.9398)
			(stroke
				(width 0)
				(type default)
			)
			(fill no)
			(layer "B.Fab")
		)
		(pad "1" smd custom
			(at 0 -0.4445 90)
			(size 0.1397 0.1397)
			(layers "B.Cu" "B.Mask" "B.Paste")
			(net "P0V9_GSNS")
			(options
				(clearance outline)
				(anchor circle)
			)
			(primitives
				(gr_poly
					(pts
						(arc
							(start -0.1778 0.2794)
							(mid -0.249642 0.249642)
							(end -0.2794 0.1778)
						)
						(arc
							(start -0.2794 -0.1778)
							(mid -0.249642 -0.249642)
							(end -0.1778 -0.2794)
						)
						(arc
							(start 0.1778 -0.2794)
							(mid 0.249642 -0.249642)
							(end 0.2794 -0.1778)
						)
						(arc
							(start 0.2794 0.1778)
							(mid 0.249642 0.249642)
							(end 0.1778 0.2794)
						)
					)
					(width 0)
					(fill yes)
				)
			)
		)
		(pad "2" smd custom
			(at 0 0.4445 90)
			(size 0.1397 0.1397)
			(layers "B.Cu" "B.Mask" "B.Paste")
			(net "GND")
			(options
				(clearance outline)
				(anchor circle)
			)
			(primitives
				(gr_poly
					(pts
						(arc
							(start -0.1778 0.2794)
							(mid -0.249642 0.249642)
							(end -0.2794 0.1778)
						)
						(arc
							(start -0.2794 -0.1778)
							(mid -0.249642 -0.249642)
							(end -0.1778 -0.2794)
						)
						(arc
							(start 0.1778 -0.2794)
							(mid 0.249642 -0.249642)
							(end 0.2794 -0.1778)
						)
						(arc
							(start 0.2794 0.1778)
							(mid 0.249642 0.249642)
							(end 0.1778 0.2794)
						)
					)
					(width 0)
					(fill yes)
				)
			)
		)
	)
)
